# S9S_MB_2U (Grand Teton) — schematic netlist excerpt (pin names and nets, part order shuffled) for the footprints in the layout excerpt that follows; sources: Cadence DE-HDL packaged netlist, KiCad conversion of 03242023_DA0F0TMBIJ0_F0T_Motherboard_J_brd_V01_OCP.brd

J24  SCONN288_ADR50017P087CC  SCONN288_ADR50017-P087CC IO  pkg DDR288S_1-1VXB  page 105
  VIN_BULK0  = P12V_S3_AUX_CPU1_NVDIMM
  RFU0  = TP_CHD_CPU1_DIMM2_FRU_0
  VIN_MGMT  = P3V3_AUX
  HSCL  = I3C_SPD_DDRABCD_CPU1_LVC1_SCL_7
  HSDA  = I3C_SPD_DDRABCD_CPU1_LVC1_SDA
  VSS0  = GND
  DQ0_A  = M_D_CPU1_SA_DQ<0>
  VSS1  = GND
  DQ1_A  = M_D_CPU1_SA_DQ<1>
  VSS2  = GND
  DQS0_A_T  = M_D_CPU1_SA_DQS_DP<0>
  DQS0_A_C  = M_D_CPU1_SA_DQS_DN<0>
  VSS3  = GND
  DQ4_A  = M_D_CPU1_SA_DQ<4>
  VSS4  = GND
  DQ5_A  = M_D_CPU1_SA_DQ<5>
  VSS5  = GND
  DQ8_A  = M_D_CPU1_SA_DQ<8>
  VSS6  = GND
  DQ9_A  = M_D_CPU1_SA_DQ<9>
  VSS7  = GND
  DQS1_A_T  = M_D_CPU1_SA_DQS_DP<1>
  DQS1_A_C  = M_D_CPU1_SA_DQS_DN<1>
  VSS8  = GND
  DQ12_A  = M_D_CPU1_SA_DQ<12>
  VSS9  = GND
  DQ13_A  = M_D_CPU1_SA_DQ<13>
  VSS10  = GND
  DQ16_A  = M_D_CPU1_SA_DQ<16>
  VSS11  = GND
  DQ17_A  = M_D_CPU1_SA_DQ<17>
  VSS12  = GND
  DQS2_A_T  = M_D_CPU1_SA_DQS_DP<2>
  DQS2_A_C  = M_D_CPU1_SA_DQS_DN<2>
  VSS13  = GND
  DQ20_A  = M_D_CPU1_SA_DQ<20>
  VSS14  = GND
  DQ21_A  = M_D_CPU1_SA_DQ<21>
  VSS15  = GND
  DQ24_A  = M_D_CPU1_SA_DQ<24>
  VSS16  = GND
  DQ25_A  = M_D_CPU1_SA_DQ<25>
  VSS17  = GND
  DQS3_A_T  = M_D_CPU1_SA_DQS_DP<3>
  DQS3_A_C  = M_D_CPU1_SA_DQS_DN<3>
  VSS18  = GND
  DQ28_A  = M_D_CPU1_SA_DQ<28>
  VSS19  = GND
  DQ29_A  = M_D_CPU1_SA_DQ<29>
  VSS20  = GND
  CB0_A  = M_D_CPU1_SA_CB<0>
  VSS21  = GND
  CB1_A  = M_D_CPU1_SA_CB<1>
  VSS22  = GND
  DQS4_A_T  = M_D_CPU1_SA_DQS_DP<4>
  DQS4_A_C  = M_D_CPU1_SA_DQS_DN<4>
  VSS23  = GND
  CB4_A  = M_D_CPU1_SA_CB<4>
  VSS24  = GND
  CB5_A  = M_D_CPU1_SA_CB<5>
  VSS25  = GND
  ALERT_N  = M_D_CPU1_ALERT_N
  VSS26  = GND
  CS0_A_N  = M_D_CPU1_SA_CS_N<2>
  VSS27  = GND
  CA0_A  = M_D_CPU1_SA_CA<0>
  VSS28  = GND
  CA2_A  = M_D_CPU1_SA_CA<2>
  VSS29  = GND
  CA4_A  = M_D_CPU1_SA_CA<4>
  VSS30  = GND
  CA6_A  = M_D_CPU1_SA_CA<6>
  VSS31  = GND
  PAR_A  = M_D_CPU1_SA_PAR
  VSS32  = GND
  CA0_B  = M_D_CPU1_SB_CA<0>
  VSS33  = GND
  CA2_B  = M_D_CPU1_SB_CA<2>
  VSS34  = GND
  CA4_B  = M_D_CPU1_SB_CA<4>
  VSS35  = GND
  CA6_B  = M_D_CPU1_SB_CA<6>
  VSS36  = GND
  CS0_B_N  = M_D_CPU1_SB_CS_N<2>
  VSS37  = GND
  \lbd||rsp_a_n\  = M_D_CPU1_SA_RSP<1>
  \lbs||rsp_b_n\  = M_D_CPU1_SB_RSP<1>
  VSS38  = GND
  CB4_B  = M_D_CPU1_SB_CB<4>
  VSS39  = GND
  CB5_B  = M_D_CPU1_SB_CB<5>
  VSS40  = GND
  \dqs9_b_t||tdqs9_b_t||dbi4_b_n\  = M_D_CPU1_SB_DQS_DP<9>
  \dqs9_b_c||tdqs9_b_c\  = M_D_CPU1_SB_DQS_DN<9>
  VSS41  = GND
  CB0_B  = M_D_CPU1_SB_CB<0>
  VSS42  = GND
  CB1_B  = M_D_CPU1_SB_CB<1>
  VSS43  = GND
  DQ0_B  = M_D_CPU1_SB_DQ<0>
  VSS44  = GND
  DQ1_B  = M_D_CPU1_SB_DQ<1>
  VSS45  = GND
  DQS0_B_T  = M_D_CPU1_SB_DQS_DP<0>
  DQS0_B_C  = M_D_CPU1_SB_DQS_DN<0>
  VSS46  = GND
  DQ4_B  = M_D_CPU1_SB_DQ<4>
  VSS47  = GND
  DQ5_B  = M_D_CPU1_SB_DQ<5>
  VSS48  = GND
  DQ8_B  = M_D_CPU1_SB_DQ<8>
  VSS49  = GND
  DQ9_B  = M_D_CPU1_SB_DQ<9>
  VSS50  = GND
  DQS1_B_T  = M_D_CPU1_SB_DQS_DP<1>
  DQS1_B_C  = M_D_CPU1_SB_DQS_DN<1>
  VSS51  = GND
  DQ12_B  = M_D_CPU1_SB_DQ<12>
  VSS52  = GND
  DQ13_B  = M_D_CPU1_SB_DQ<13>
  VSS53  = GND
  DQ16_B  = M_D_CPU1_SB_DQ<16>
  VSS54  = GND
  DQ17_B  = M_D_CPU1_SB_DQ<17>
  VSS55  = GND
  DQS2_B_T  = M_D_CPU1_SB_DQS_DP<2>
  DQS2_B_C  = M_D_CPU1_SB_DQS_DN<2>
  VSS56  = GND
  DQ20_B  = M_D_CPU1_SB_DQ<20>
  VSS57  = GND
  DQ21_B  = M_D_CPU1_SB_DQ<21>
  VSS58  = GND
  DQ24_B  = M_D_CPU1_SB_DQ<24>
  VSS59  = GND
  DQ25_B  = M_D_CPU1_SB_DQ<25>
  VSS60  = GND
  DQS3_B_T  = M_D_CPU1_SB_DQS_DP<3>
  DQS3_B_C  = M_D_CPU1_SB_DQS_DN<3>
  VSS61  = GND
  DQ28_B  = M_D_CPU1_SB_DQ<28>
  VSS62  = GND
  DQ29_B  = M_D_CPU1_SB_DQ<29>
  VSS63  = GND
  RFU1  = TP_CHD_CPU1_DIMM2_FRU_1
  VIN_BULK1  = P12V_S3_AUX_CPU1_NVDIMM
  VIN_BULK2  = P12V_S3_AUX_CPU1_NVDIMM
  \pwr_good||fail_n\  = PWRGD_CHD_CPU1_DIMM2
  HSA  = PD_CHD_CPU1_DIMM2_SAA
  RFU2  = TP_CHD_CPU1_DIMM2_FRU_2
  RFU3  = TP_CHD_CPU1_DIMM2_FRU_3
  VSS64  = GND
  DQ2_A  = M_D_CPU1_SA_DQ<2>
  VSS65  = GND
  DQ3_A  = M_D_CPU1_SA_DQ<3>
  VSS66  = GND
  \dqs5_a_c||tdqs5_a_c||dqs5_a_t||tdqs5_a_t\  = M_D_CPU1_SA_DQS_DN<5>
  \dqs5_a_t||tdqs5_a_t\  = M_D_CPU1_SA_DQS_DP<5>
  VSS67  = GND
  DQ6_A  = M_D_CPU1_SA_DQ<6>
  VSS68  = GND
  DQ7_A  = M_D_CPU1_SA_DQ<7>
  VSS69  = GND
  DQ10_A  = M_D_CPU1_SA_DQ<10>
  VSS70  = GND
  DQ11_A  = M_D_CPU1_SA_DQ<11>
  VSS71  = GND
  \dqs6_a_c||tdqs6_a_c||dqs6_a_t||tdqs6_a_t\  = M_D_CPU1_SA_DQS_DN<6>
  \dqs6_a_t||tdqs6_a_t\  = M_D_CPU1_SA_DQS_DP<6>
  VSS72  = GND
  DQ14_A  = M_D_CPU1_SA_DQ<14>
  VSS73  = GND
  DQ15_A  = M_D_CPU1_SA_DQ<15>
  VSS74  = GND
  DQ18_A  = M_D_CPU1_SA_DQ<18>
  VSS75  = GND
  DQ19_A  = M_D_CPU1_SA_DQ<19>
  VSS76  = GND
  \dqs7_a_c||tdqs7_a_c\  = M_D_CPU1_SA_DQS_DN<7>
  \dqs7_a_t||tdqs7_a_t\  = M_D_CPU1_SA_DQS_DP<7>
  VSS77  = GND
  DQ22_A  = M_D_CPU1_SA_DQ<22>
  VSS78  = GND
  DQ23_A  = M_D_CPU1_SA_DQ<23>
  VSS79  = GND
  DQ26_A  = M_D_CPU1_SA_DQ<26>
  VSS80  = GND
  DQ27_A  = M_D_CPU1_SA_DQ<27>
  VSS81  = GND
  \dqs8_a_c||tdqs8_a_c\  = M_D_CPU1_SA_DQS_DN<8>
  \dqs8_a_t||tdqs8_a_t\  = M_D_CPU1_SA_DQS_DP<8>
  VSS82  = GND
  DQ30_A  = M_D_CPU1_SA_DQ<30>
  VSS83  = GND
  DQ31_A  = M_D_CPU1_SA_DQ<31>
  VSS84  = GND
  CB2_A  = M_D_CPU1_SA_CB<2>
  VSS85  = GND
  CB3_A  = M_D_CPU1_SA_CB<3>
  VSS86  = GND
  \dqs9_a_c||tdqs9_a_c\  = M_D_CPU1_SA_DQS_DN<9>
  \dqs9_a_t||tdqs9_a_t\  = M_D_CPU1_SA_DQS_DP<9>
  VSS87  = GND
  CB6_A  = M_D_CPU1_SA_CB<6>
  VSS88  = GND
  CB7_A  = M_D_CPU1_SA_CB<7>
  VSS89  = GND
  RESET_N  = RST_M_CD_CPU1_FPGA_N
  VSS90  = GND
  CS1_A_N  = M_D_CPU1_SA_CS_N<3>
  VSS91  = GND
  CA1_A  = M_D_CPU1_SA_CA<1>
  VSS92  = GND
  CA3_A  = M_D_CPU1_SA_CA<3>
  VSS93  = GND
  CA5_A  = M_D_CPU1_SA_CA<5>
  VSS94  = GND
  CK_T  = M_D_CPU1_CLK_DP<1>
  CK_C  = M_D_CPU1_CLK_DN<1>
  VSS95  = GND
  RFU4  = TP_CHD_CPU1_DIMM2_FRU_4
  CA1_B  = M_D_CPU1_SB_CA<1>
  VSS96  = GND
  CA3_B  = M_D_CPU1_SB_CA<3>
  VSS97  = GND
  CA5_B  = M_D_CPU1_SB_CA<5>
  VSS98  = GND
  PAR_B  = M_D_CPU1_SB_PAR
  VSS99  = GND
  CS1_B_N  = M_D_CPU1_SB_CS_N<3>
  VSS100  = GND
  RFU5  = TP_CHD_CPU1_DIMM2_FRU_5
  RFU6  = TP_CHD_CPU1_DIMM2_FRU_6
  VSS101  = GND
  CB6_B  = M_D_CPU1_SB_CB<6>
  VSS102  = GND
  CB7_B  = M_D_CPU1_SB_CB<7>
  VSS103  = GND
  DQS4_B_C  = M_D_CPU1_SB_DQS_DN<4>
  DQS4_B_T  = M_D_CPU1_SB_DQS_DP<4>
  VSS104  = GND
  CB2_B  = M_D_CPU1_SB_CB<2>
  VSS105  = GND
  CB3_B  = M_D_CPU1_SB_CB<3>
  VSS106  = GND
  DQ2_B  = M_D_CPU1_SB_DQ<2>
  VSS107  = GND
  DQ3_B  = M_D_CPU1_SB_DQ<3>
  VSS108  = GND
  \dqs5_b_c||tdqs5_b_c\  = M_D_CPU1_SB_DQS_DN<5>
  \dqs5_b_t||tdqs5_b_t\  = M_D_CPU1_SB_DQS_DP<5>
  VSS109  = GND
  DQ6_B  = M_D_CPU1_SB_DQ<6>
  VSS110  = GND
  DQ7_B  = M_D_CPU1_SB_DQ<7>
  VSS111  = GND
  DQ10_B  = M_D_CPU1_SB_DQ<10>
  VSS112  = GND
  DQ11_B  = M_D_CPU1_SB_DQ<11>
  VSS113  = GND
  \dqs6_b_c||tdqs6_b_c\  = M_D_CPU1_SB_DQS_DN<6>
  \dqs6_b_t||tdqs6_b_t\  = M_D_CPU1_SB_DQS_DP<6>
  VSS114  = GND
  DQ14_B  = M_D_CPU1_SB_DQ<14>
  VSS115  = GND
  DQ15_B  = M_D_CPU1_SB_DQ<15>
  VSS116  = GND
  DQ18_B  = M_D_CPU1_SB_DQ<18>
  VSS117  = GND
  DQ19_B  = M_D_CPU1_SB_DQ<19>
  VSS118  = GND
  \dqs7_b_c||tdqs7_b_c\  = M_D_CPU1_SB_DQS_DN<7>
  \dqs7_b_t||tdqs7_b_t\  = M_D_CPU1_SB_DQS_DP<7>
  VSS119  = GND
  DQ22_B  = M_D_CPU1_SB_DQ<22>
  VSS120  = GND
  DQ23_B  = M_D_CPU1_SB_DQ<23>
  VSS121  = GND
  DQ26_B  = M_D_CPU1_SB_DQ<26>
  VSS122  = GND
  DQ27_B  = M_D_CPU1_SB_DQ<27>
  VSS123  = GND
  \dqs8_b_c||tdqs8_b_c\  = M_D_CPU1_SB_DQS_DN<8>
  \dqs8_b_t||tdqs8_b_t\  = M_D_CPU1_SB_DQS_DP<8>
  VSS124  = GND
  DQ30_B  = M_D_CPU1_SB_DQ<30>
  VSS125  = GND
  DQ31_B  = M_D_CPU1_SB_DQ<31>
  VSS126  = GND
  G1  = GND
  G2  = GND
  G3  = GND

(kicad_pcb
	(version 20260206)
	(generator "pcbnew")
	(generator_version "10.0")
	(general
		(thickness 1.6)
		(legacy_teardrops no)
	)
	(paper "A4")
	(title_block
		(title "03242023_DA0F0TMBIJ0_F0T_Motherboard_J_brd_V01_OCP.brd")
		(comment 1 "Grand Teton / footprint 1660 of 6105 (J24), pads 92-137 of 291")
	)
	(layers
		(0 "F.Cu" signal "TOP")
		(4 "In1.Cu" signal "GND")
		(6 "In2.Cu" signal "IN1")
		(8 "In3.Cu" signal "GND1")
		(10 "In4.Cu" signal "IN2")
		(12 "In5.Cu" signal "GND2")
		(14 "In6.Cu" signal "IN3")
		(16 "In7.Cu" signal "GND3")
		(18 "In8.Cu" signal "VCC")
		(20 "In9.Cu" signal "VCC1")
		(22 "In10.Cu" signal "GND4")
		(24 "In11.Cu" signal "IN4")
		(26 "In12.Cu" signal "GND5")
		(28 "In13.Cu" signal "IN5")
		(30 "In14.Cu" signal "GND6")
		(32 "In15.Cu" signal "IN6")
		(34 "In16.Cu" signal "GND7")
		(2 "B.Cu" signal "BOTTOM")
		(9 "F.Adhes" user "F.Adhesive")
		(11 "B.Adhes" user "B.Adhesive")
		(13 "F.Paste" user "Package Geometry/Pastemask Top")
		(15 "B.Paste" user "Package Geometry/Pastemask Bottom")
		(5 "F.SilkS" user "Ref Des/Silkscreen Top")
		(7 "B.SilkS" user "Ref Des/Silkscreen Bottom")
		(1 "F.Mask" user "Board Geometry/Soldermask Top")
		(3 "B.Mask" user "Board Geometry/Soldermask Bottom")
		(17 "Dwgs.User" user "User.Drawings")
		(19 "Cmts.User" user "User.Comments")
		(21 "Eco1.User" user "User.Eco1")
		(23 "Eco2.User" user "User.Eco2")
		(25 "Edge.Cuts" user "Board Geometry/Outline")
		(27 "Margin" user)
		(31 "F.CrtYd" user "Package Geometry/Place Bound Top")
		(29 "B.CrtYd" user "Package Geometry/Place Bound Bottom")
		(35 "F.Fab" user "Ref Des/Assembly Top")
		(33 "B.Fab" user "Ref Des/Assembly Bottom")
	)
	(footprint ""
		(layer "F.Cu")
		(at 17.73428 -258.091686)
		(property "Reference" "J24"
			(at -3.0607 -81.901792 0)
			(unlocked yes)
			(layer "F.SilkS")
			(effects
				(font
					(size 0.7874 0.5842)
					(thickness 0.1524)
				)
				(justify left)
			)
		)
		(property "Value" ""
			(at 0 0 0)
			(layer "F.Fab")
			(effects
				(font
					(size 1.27 1.27)
				)
			)
		)
		(duplicate_pad_numbers_are_jumpers no)
		(pad "92" smd rect
			(at -2.050034 19.12493 270)
			(size 0.519938 1.4986)
			(layers "F.Cu" "F.Mask" "F.Paste")
			(net "GND")
		)
		(pad "93" smd rect
			(at -2.050034 19.975068 270)
			(size 0.519938 1.4986)
			(layers "F.Cu" "F.Mask" "F.Paste")
			(net "M_D_CPU1_SB_DQS_DP<9>")
		)
		(pad "94" smd rect
			(at -2.050034 20.824952 270)
			(size 0.519938 1.4986)
			(layers "F.Cu" "F.Mask" "F.Paste")
			(net "M_D_CPU1_SB_DQS_DN<9>")
		)
		(pad "95" smd rect
			(at -2.050034 21.67509 270)
			(size 0.519938 1.4986)
			(layers "F.Cu" "F.Mask" "F.Paste")
			(net "GND")
		)
		(pad "96" smd rect
			(at -2.050034 22.524974 270)
			(size 0.519938 1.4986)
			(layers "F.Cu" "F.Mask" "F.Paste")
			(net "M_D_CPU1_SB_CB<0>")
		)
		(pad "97" smd rect
			(at -2.050034 23.375112 270)
			(size 0.519938 1.4986)
			(layers "F.Cu" "F.Mask" "F.Paste")
			(net "GND")
		)
		(pad "98" smd rect
			(at -2.050034 24.224996 270)
			(size 0.519938 1.4986)
			(layers "F.Cu" "F.Mask" "F.Paste")
			(net "M_D_CPU1_SB_CB<1>")
		)
		(pad "99" smd rect
			(at -2.050034 25.07488 270)
			(size 0.519938 1.4986)
			(layers "F.Cu" "F.Mask" "F.Paste")
			(net "GND")
		)
		(pad "100" smd rect
			(at -2.050034 25.925018 270)
			(size 0.519938 1.4986)
			(layers "F.Cu" "F.Mask" "F.Paste")
			(net "M_D_CPU1_SB_DQ<0>")
		)
		(pad "101" smd rect
			(at -2.050034 26.774902 270)
			(size 0.519938 1.4986)
			(layers "F.Cu" "F.Mask" "F.Paste")
			(net "GND")
		)
		(pad "102" smd rect
			(at -2.050034 27.62504 270)
			(size 0.519938 1.4986)
			(layers "F.Cu" "F.Mask" "F.Paste")
			(net "M_D_CPU1_SB_DQ<1>")
		)
		(pad "103" smd rect
			(at -2.050034 28.474924 270)
			(size 0.519938 1.4986)
			(layers "F.Cu" "F.Mask" "F.Paste")
			(net "GND")
		)
		(pad "104" smd rect
			(at -2.050034 29.325062 270)
			(size 0.519938 1.4986)
			(layers "F.Cu" "F.Mask" "F.Paste")
			(net "M_D_CPU1_SB_DQS_DP<0>")
		)
		(pad "105" smd rect
			(at -2.050034 30.174946 270)
			(size 0.519938 1.4986)
			(layers "F.Cu" "F.Mask" "F.Paste")
			(net "M_D_CPU1_SB_DQS_DN<0>")
		)
		(pad "106" smd rect
			(at -2.050034 31.025084 270)
			(size 0.519938 1.4986)
			(layers "F.Cu" "F.Mask" "F.Paste")
			(net "GND")
		)
		(pad "107" smd rect
			(at -2.050034 31.874968 270)
			(size 0.519938 1.4986)
			(layers "F.Cu" "F.Mask" "F.Paste")
			(net "M_D_CPU1_SB_DQ<4>")
		)
		(pad "108" smd rect
			(at -2.050034 32.725106 270)
			(size 0.519938 1.4986)
			(layers "F.Cu" "F.Mask" "F.Paste")
			(net "GND")
		)
		(pad "109" smd rect
			(at -2.050034 33.57499 270)
			(size 0.519938 1.4986)
			(layers "F.Cu" "F.Mask" "F.Paste")
			(net "M_D_CPU1_SB_DQ<5>")
		)
		(pad "110" smd rect
			(at -2.050034 34.425128 270)
			(size 0.519938 1.4986)
			(layers "F.Cu" "F.Mask" "F.Paste")
			(net "GND")
		)
		(pad "111" smd rect
			(at -2.050034 35.275012 270)
			(size 0.519938 1.4986)
			(layers "F.Cu" "F.Mask" "F.Paste")
			(net "M_D_CPU1_SB_DQ<8>")
		)
		(pad "112" smd rect
			(at -2.050034 36.124896 270)
			(size 0.519938 1.4986)
			(layers "F.Cu" "F.Mask" "F.Paste")
			(net "GND")
		)
		(pad "113" smd rect
			(at -2.050034 36.975034 270)
			(size 0.519938 1.4986)
			(layers "F.Cu" "F.Mask" "F.Paste")
			(net "M_D_CPU1_SB_DQ<9>")
		)
		(pad "114" smd rect
			(at -2.050034 37.824918 270)
			(size 0.519938 1.4986)
			(layers "F.Cu" "F.Mask" "F.Paste")
			(net "GND")
		)
		(pad "115" smd rect
			(at -2.050034 38.675056 270)
			(size 0.519938 1.4986)
			(layers "F.Cu" "F.Mask" "F.Paste")
			(net "M_D_CPU1_SB_DQS_DP<1>")
		)
		(pad "116" smd rect
			(at -2.050034 39.52494 270)
			(size 0.519938 1.4986)
			(layers "F.Cu" "F.Mask" "F.Paste")
			(net "M_D_CPU1_SB_DQS_DN<1>")
		)
		(pad "117" smd rect
			(at -2.050034 40.375078 270)
			(size 0.519938 1.4986)
			(layers "F.Cu" "F.Mask" "F.Paste")
			(net "GND")
		)
		(pad "118" smd rect
			(at -2.050034 41.224962 270)
			(size 0.519938 1.4986)
			(layers "F.Cu" "F.Mask" "F.Paste")
			(net "M_D_CPU1_SB_DQ<12>")
		)
		(pad "119" smd rect
			(at -2.050034 42.0751 270)
			(size 0.519938 1.4986)
			(layers "F.Cu" "F.Mask" "F.Paste")
			(net "GND")
		)
		(pad "120" smd rect
			(at -2.050034 42.924984 270)
			(size 0.519938 1.4986)
			(layers "F.Cu" "F.Mask" "F.Paste")
			(net "M_D_CPU1_SB_DQ<13>")
		)
		(pad "121" smd rect
			(at -2.050034 43.775122 270)
			(size 0.519938 1.4986)
			(layers "F.Cu" "F.Mask" "F.Paste")
			(net "GND")
		)
		(pad "122" smd rect
			(at -2.050034 44.625006 270)
			(size 0.519938 1.4986)
			(layers "F.Cu" "F.Mask" "F.Paste")
			(net "M_D_CPU1_SB_DQ<16>")
		)
		(pad "123" smd rect
			(at -2.050034 45.47489 270)
			(size 0.519938 1.4986)
			(layers "F.Cu" "F.Mask" "F.Paste")
			(net "GND")
		)
		(pad "124" smd rect
			(at -2.050034 46.325028 270)
			(size 0.519938 1.4986)
			(layers "F.Cu" "F.Mask" "F.Paste")
			(net "M_D_CPU1_SB_DQ<17>")
		)
		(pad "125" smd rect
			(at -2.050034 47.174912 270)
			(size 0.519938 1.4986)
			(layers "F.Cu" "F.Mask" "F.Paste")
			(net "GND")
		)
		(pad "126" smd rect
			(at -2.050034 48.02505 270)
			(size 0.519938 1.4986)
			(layers "F.Cu" "F.Mask" "F.Paste")
			(net "M_D_CPU1_SB_DQS_DP<2>")
		)
		(pad "127" smd rect
			(at -2.050034 48.874934 270)
			(size 0.519938 1.4986)
			(layers "F.Cu" "F.Mask" "F.Paste")
			(net "M_D_CPU1_SB_DQS_DN<2>")
		)
		(pad "128" smd rect
			(at -2.050034 49.725072 270)
			(size 0.519938 1.4986)
			(layers "F.Cu" "F.Mask" "F.Paste")
			(net "GND")
		)
		(pad "129" smd rect
			(at -2.050034 50.574956 270)
			(size 0.519938 1.4986)
			(layers "F.Cu" "F.Mask" "F.Paste")
			(net "M_D_CPU1_SB_DQ<20>")
		)
		(pad "130" smd rect
			(at -2.050034 51.425094 270)
			(size 0.519938 1.4986)
			(layers "F.Cu" "F.Mask" "F.Paste")
			(net "GND")
		)
		(pad "131" smd rect
			(at -2.050034 52.274978 270)
			(size 0.519938 1.4986)
			(layers "F.Cu" "F.Mask" "F.Paste")
			(net "M_D_CPU1_SB_DQ<21>")
		)
		(pad "132" smd rect
			(at -2.050034 53.125116 270)
			(size 0.519938 1.4986)
			(layers "F.Cu" "F.Mask" "F.Paste")
			(net "GND")
		)
		(pad "133" smd rect
			(at -2.050034 53.975 270)
			(size 0.519938 1.4986)
			(layers "F.Cu" "F.Mask" "F.Paste")
			(net "M_D_CPU1_SB_DQ<24>")
		)
		(pad "134" smd rect
			(at -2.050034 54.824884 270)
			(size 0.519938 1.4986)
			(layers "F.Cu" "F.Mask" "F.Paste")
			(net "GND")
		)
		(pad "135" smd rect
			(at -2.050034 55.675022 270)
			(size 0.519938 1.4986)
			(layers "F.Cu" "F.Mask" "F.Paste")
			(net "M_D_CPU1_SB_DQ<25>")
		)
		(pad "136" smd rect
			(at -2.050034 56.524906 270)
			(size 0.519938 1.4986)
			(layers "F.Cu" "F.Mask" "F.Paste")
			(net "GND")
		)
		(pad "137" smd rect
			(at -2.050034 57.375044 270)
			(size 0.519938 1.4986)
			(layers "F.Cu" "F.Mask" "F.Paste")
			(net "M_D_CPU1_SB_DQS_DP<3>")
		)
	)
)
